# S9S_MB_2U (Grand Teton) — schematic netlist excerpt (pin names and nets, part order shuffled) for the footprints in the layout excerpt that follows; sources: Cadence DE-HDL packaged netlist, KiCad conversion of 03242023_DA0F0TMBIJ0_F0T_Motherboard_J_brd_V01_OCP.brd

PR254  Q_RES  2.2 1% CHIP  pkg 0402LF  page 293 : A = PVCCFA_EHV_CPU1_PVCC ; B = PVCCINFAON_CPU1_VDD1
R2558  Q_RES  0 5% CHIP  pkg 0402LF  page 292 : A = FM_PVCCINFAON_CPU1_EN ; B = PVCCINFAON_CPU1_EN_R

(kicad_pcb
	(version 20260206)
	(generator "pcbnew")
	(generator_version "10.0")
	(general
		(thickness 1.6)
		(legacy_teardrops no)
	)
	(paper "A4")
	(title_block
		(title "03242023_DA0F0TMBIJ0_F0T_Motherboard_J_brd_V01_OCP.brd")
		(comment 1 "Grand Teton / footprints 4358-4359 of 6105")
	)
	(layers
		(0 "F.Cu" signal "TOP")
		(4 "In1.Cu" signal "GND")
		(6 "In2.Cu" signal "IN1")
		(8 "In3.Cu" signal "GND1")
		(10 "In4.Cu" signal "IN2")
		(12 "In5.Cu" signal "GND2")
		(14 "In6.Cu" signal "IN3")
		(16 "In7.Cu" signal "GND3")
		(18 "In8.Cu" signal "VCC")
		(20 "In9.Cu" signal "VCC1")
		(22 "In10.Cu" signal "GND4")
		(24 "In11.Cu" signal "IN4")
		(26 "In12.Cu" signal "GND5")
		(28 "In13.Cu" signal "IN5")
		(30 "In14.Cu" signal "GND6")
		(32 "In15.Cu" signal "IN6")
		(34 "In16.Cu" signal "GND7")
		(2 "B.Cu" signal "BOTTOM")
		(9 "F.Adhes" user "F.Adhesive")
		(11 "B.Adhes" user "B.Adhesive")
		(13 "F.Paste" user "Package Geometry/Pastemask Top")
		(15 "B.Paste" user "Package Geometry/Pastemask Bottom")
		(5 "F.SilkS" user "Ref Des/Silkscreen Top")
		(7 "B.SilkS" user "Ref Des/Silkscreen Bottom")
		(1 "F.Mask" user "Board Geometry/Soldermask Top")
		(3 "B.Mask" user "Board Geometry/Soldermask Bottom")
		(17 "Dwgs.User" user "User.Drawings")
		(19 "Cmts.User" user "User.Comments")
		(21 "Eco1.User" user "User.Eco1")
		(23 "Eco2.User" user "User.Eco2")
		(25 "Edge.Cuts" user "Board Geometry/Outline")
		(27 "Margin" user)
		(31 "F.CrtYd" user "Package Geometry/Place Bound Top")
		(29 "B.CrtYd" user "Package Geometry/Place Bound Bottom")
		(35 "F.Fab" user "Ref Des/Assembly Top")
		(33 "B.Fab" user "Ref Des/Assembly Bottom")
	)
	(footprint ""
		(layer "B.Cu")
		(at 53.912516 -154.081226)
		(property "Reference" "PR254"
			(at 0 0 0)
			(layer "B.SilkS")
			(hide yes)
			(effects
				(font
					(size 1.27 1.27)
				)
				(justify mirror)
			)
		)
		(property "Value" ""
			(at 0 0 0)
			(layer "B.Fab")
			(effects
				(font
					(size 1.27 1.27)
				)
				(justify mirror)
			)
		)
		(duplicate_pad_numbers_are_jumpers no)
		(fp_line
			(start -0.7874 -0.4064)
			(end -0.7874 0.4064)
			(stroke
				(width 0.1524)
				(type default)
			)
			(layer "B.SilkS")
		)
		(fp_line
			(start -0.7874 0.4064)
			(end 0.7874 0.4064)
			(stroke
				(width 0.1524)
				(type default)
			)
			(layer "B.SilkS")
		)
		(fp_line
			(start 0.7874 -0.4064)
			(end -0.7874 -0.4064)
			(stroke
				(width 0.1524)
				(type default)
			)
			(layer "B.SilkS")
		)
		(fp_line
			(start 0.7874 0.4064)
			(end 0.7874 -0.4064)
			(stroke
				(width 0.1524)
				(type default)
			)
			(layer "B.SilkS")
		)
		(fp_line
			(start -0.67945 -0.3048)
			(end -0.67945 0.3048)
			(stroke
				(width 0.1)
				(type default)
			)
			(layer "B.Fab")
		)
		(fp_line
			(start -0.67945 0.3048)
			(end -0.120396 0.3048)
			(stroke
				(width 0.1)
				(type default)
			)
			(layer "B.Fab")
		)
		(fp_line
			(start -0.12065 -0.3048)
			(end -0.67945 -0.3048)
			(stroke
				(width 0.1)
				(type default)
			)
			(layer "B.Fab")
		)
		(fp_line
			(start -0.12065 -0.2794)
			(end -0.12065 -0.3048)
			(stroke
				(width 0.1)
				(type default)
			)
			(layer "B.Fab")
		)
		(fp_line
			(start -0.120396 0.2794)
			(end 0.12065 0.2794)
			(stroke
				(width 0.1)
				(type default)
			)
			(layer "B.Fab")
		)
		(fp_line
			(start -0.120396 0.3048)
			(end -0.120396 0.2794)
			(stroke
				(width 0.1)
				(type default)
			)
			(layer "B.Fab")
		)
		(fp_line
			(start 0.12065 -0.305054)
			(end 0.12065 -0.2794)
			(stroke
				(width 0.1)
				(type default)
			)
			(layer "B.Fab")
		)
		(fp_line
			(start 0.12065 -0.2794)
			(end -0.12065 -0.2794)
			(stroke
				(width 0.1)
				(type default)
			)
			(layer "B.Fab")
		)
		(fp_line
			(start 0.12065 0.2794)
			(end 0.12065 0.3048)
			(stroke
				(width 0.1)
				(type default)
			)
			(layer "B.Fab")
		)
		(fp_line
			(start 0.12065 0.3048)
			(end 0.67945 0.3048)
			(stroke
				(width 0.1)
				(type default)
			)
			(layer "B.Fab")
		)
		(fp_line
			(start 0.67945 -0.305054)
			(end 0.12065 -0.305054)
			(stroke
				(width 0.1)
				(type default)
			)
			(layer "B.Fab")
		)
		(fp_line
			(start 0.67945 0.3048)
			(end 0.67945 -0.305054)
			(stroke
				(width 0.1)
				(type default)
			)
			(layer "B.Fab")
		)
		(pad "1" smd circle
			(at 0.40005 0 180)
			(size 0 0)
			(layers "B.Cu" "B.Mask" "B.Paste")
			(net "PVCCFA_EHV_CPU1_PVCC")
		)
		(pad "2" smd circle
			(at -0.40005 0 180)
			(size 0 0)
			(layers "B.Cu" "B.Mask" "B.Paste")
			(net "PVCCINFAON_CPU1_VDD1")
		)
	)
	(footprint ""
		(layer "B.Cu")
		(at 36.968938 -127.41656)
		(property "Reference" "R2558"
			(at 0 0 0)
			(layer "B.SilkS")
			(hide yes)
			(effects
				(font
					(size 1.27 1.27)
				)
				(justify mirror)
			)
		)
		(property "Value" ""
			(at 0 0 0)
			(layer "B.Fab")
			(effects
				(font
					(size 1.27 1.27)
				)
				(justify mirror)
			)
		)
		(duplicate_pad_numbers_are_jumpers no)
		(fp_line
			(start -0.7874 -0.4064)
			(end -0.7874 0.4064)
			(stroke
				(width 0.1524)
				(type default)
			)
			(layer "B.SilkS")
		)
		(fp_line
			(start -0.7874 0.4064)
			(end 0.7874 0.4064)
			(stroke
				(width 0.1524)
				(type default)
			)
			(layer "B.SilkS")
		)
		(fp_line
			(start 0.7874 -0.4064)
			(end -0.7874 -0.4064)
			(stroke
				(width 0.1524)
				(type default)
			)
			(layer "B.SilkS")
		)
		(fp_line
			(start 0.7874 0.4064)
			(end 0.7874 -0.4064)
			(stroke
				(width 0.1524)
				(type default)
			)
			(layer "B.SilkS")
		)
		(fp_line
			(start -0.67945 -0.3048)
			(end -0.67945 0.3048)
			(stroke
				(width 0.1)
				(type default)
			)
			(layer "B.Fab")
		)
		(fp_line
			(start -0.67945 0.3048)
			(end -0.120396 0.3048)
			(stroke
				(width 0.1)
				(type default)
			)
			(layer "B.Fab")
		)
		(fp_line
			(start -0.12065 -0.3048)
			(end -0.67945 -0.3048)
			(stroke
				(width 0.1)
				(type default)
			)
			(layer "B.Fab")
		)
		(fp_line
			(start -0.12065 -0.2794)
			(end -0.12065 -0.3048)
			(stroke
				(width 0.1)
				(type default)
			)
			(layer "B.Fab")
		)
		(fp_line
			(start -0.120396 0.2794)
			(end 0.12065 0.2794)
			(stroke
				(width 0.1)
				(type default)
			)
			(layer "B.Fab")
		)
		(fp_line
			(start -0.120396 0.3048)
			(end -0.120396 0.2794)
			(stroke
				(width 0.1)
				(type default)
			)
			(layer "B.Fab")
		)
		(fp_line
			(start 0.12065 -0.305054)
			(end 0.12065 -0.2794)
			(stroke
				(width 0.1)
				(type default)
			)
			(layer "B.Fab")
		)
		(fp_line
			(start 0.12065 -0.2794)
			(end -0.12065 -0.2794)
			(stroke
				(width 0.1)
				(type default)
			)
			(layer "B.Fab")
		)
		(fp_line
			(start 0.12065 0.2794)
			(end 0.12065 0.3048)
			(stroke
				(width 0.1)
				(type default)
			)
			(layer "B.Fab")
		)
		(fp_line
			(start 0.12065 0.3048)
			(end 0.67945 0.3048)
			(stroke
				(width 0.1)
				(type default)
			)
			(layer "B.Fab")
		)
		(fp_line
			(start 0.67945 -0.305054)
			(end 0.12065 -0.305054)
			(stroke
				(width 0.1)
				(type default)
			)
			(layer "B.Fab")
		)
		(fp_line
			(start 0.67945 0.3048)
			(end 0.67945 -0.305054)
			(stroke
				(width 0.1)
				(type default)
			)
			(layer "B.Fab")
		)
		(pad "1" smd circle
			(at 0.40005 0 180)
			(size 0 0)
			(layers "B.Cu" "B.Mask" "B.Paste")
			(net "FM_PVCCINFAON_CPU1_EN")
		)
		(pad "2" smd circle
			(at -0.40005 0 180)
			(size 0 0)
			(layers "B.Cu" "B.Mask" "B.Paste")
			(net "PVCCINFAON_CPU1_EN_R")
		)
	)
)
